# COM Express 7 Baseboard — KiCad project settings (.kicad_pro: net classes, design rules, text variables)
{
  "board": {
    "3dviewports": [],
    "design_settings": {
      "defaults": {
        "apply_defaults_to_fp_fields": false,
        "apply_defaults_to_fp_shapes": false,
        "apply_defaults_to_fp_text": false,
        "board_outline_line_width": 0.1,
        "copper_line_width": 0.2,
        "copper_text_italic": false,
        "copper_text_size_h": 1.5,
        "copper_text_size_v": 1.5,
        "copper_text_thickness": 0.3,
        "copper_text_upright": false,
        "courtyard_line_width": 0.05,
        "dimension_precision": 4,
        "dimension_units": 3,
        "dimensions": {
          "arrow_length": 1270000,
          "extension_offset": 500000,
          "keep_text_aligned": true,
          "suppress_zeroes": false,
          "text_position": 0,
          "units_format": 1
        },
        "fab_line_width": 0.1,
        "fab_text_italic": false,
        "fab_text_size_h": 1.0,
        "fab_text_size_v": 1.0,
        "fab_text_thickness": 0.15,
        "fab_text_upright": false,
        "other_line_width": 0.15,
        "other_text_italic": false,
        "other_text_size_h": 1.0,
        "other_text_size_v": 1.0,
        "other_text_thickness": 0.15,
        "other_text_upright": false,
        "pads": {
          "drill": 0.0,
          "height": 0.3,
          "width": 0.875
        },
        "silk_line_width": 0.15,
        "silk_text_italic": false,
        "silk_text_size_h": 1.0,
        "silk_text_size_v": 1.0,
        "silk_text_thickness": 0.15,
        "silk_text_upright": false,
        "zones": {
          "min_clearance": 0.15
        }
      },
      "diff_pair_dimensions": [
        {
          "gap": 0.0,
          "via_gap": 0.0,
          "width": 0.0
        }
      ],
      "drc_exclusions": [],
      "meta": {
        "version": 2
      },
      "rule_severities": {
        "annular_width": "error",
        "clearance": "error",
        "connection_width": "warning",
        "copper_edge_clearance": "error",
        "copper_sliver": "warning",
        "courtyards_overlap": "error",
        "creepage": "error",
        "diff_pair_gap_out_of_range": "error",
        "diff_pair_uncoupled_length_too_long": "error",
        "drill_out_of_range": "error",
        "duplicate_footprints": "warning",
        "extra_footprint": "warning",
        "footprint": "error",
        "footprint_filters_mismatch": "ignore",
        "footprint_symbol_mismatch": "warning",
        "footprint_type_mismatch": "ignore",
        "hole_clearance": "error",
        "hole_near_hole": "error",
        "hole_to_hole": "error",
        "holes_co_located": "warning",
        "invalid_outline": "error",
        "isolated_copper": "warning",
        "item_on_disabled_layer": "error",
        "items_not_allowed": "error",
        "length_out_of_range": "ignore",
        "lib_footprint_issues": "warning",
        "lib_footprint_mismatch": "warning",
        "malformed_courtyard": "error",
        "microvia_drill_out_of_range": "error",
        "mirrored_text_on_front_layer": "warning",
        "missing_courtyard": "warning",
        "missing_footprint": "warning",
        "net_conflict": "warning",
        "nonmirrored_text_on_back_layer": "warning",
        "npth_inside_courtyard": "warning",
        "padstack": "error",
        "pth_inside_courtyard": "warning",
        "shorting_items": "error",
        "silk_edge_clearance": "warning",
        "silk_over_copper": "warning",
        "silk_overlap": "warning",
        "skew_out_of_range": "ignore",
        "solder_mask_bridge": "error",
        "starved_thermal": "error",
        "text_height": "warning",
        "text_on_edge_cuts": "error",
        "text_thickness": "warning",
        "through_hole_pad_without_hole": "error",
        "too_many_vias": "error",
        "track_angle": "error",
        "track_dangling": "warning",
        "track_segment_length": "error",
        "track_width": "error",
        "tracks_crossing": "error",
        "unconnected_items": "error",
        "unresolved_variable": "error",
        "via_dangling": "warning",
        "zones_intersect": "error"
      },
      "rules": {
        "max_error": 0.005,
        "min_clearance": 0.125,
        "min_connection": 0.125,
        "min_copper_edge_clearance": 0.4,
        "min_groove_width": 0.0,
        "min_hole_clearance": 0.2,
        "min_hole_to_hole": 0.25,
        "min_microvia_diameter": 0.2,
        "min_microvia_drill": 0.1,
        "min_resolved_spokes": 1,
        "min_silk_clearance": 0.0,
        "min_text_height": 0.6,
        "min_text_thickness": 0.12,
        "min_through_hole_diameter": 0.1,
        "min_track_width": 0.125,
        "min_via_annular_width": 0.125,
        "min_via_diameter": 0.45,
        "solder_mask_clearance": 0.0,
        "solder_mask_min_width": 0.0,
        "solder_mask_to_copper_clearance": 0.0,
        "use_height_for_length_calcs": true
      },
      "teardrop_options": [
        {
          "td_onpthpad": true,
          "td_onroundshapesonly": false,
          "td_onsmdpad": true,
          "td_ontrackend": true,
          "td_onvia": true
        }
      ],
      "teardrop_parameters": [
        {
          "td_allow_use_two_tracks": true,
          "td_curve_segcount": 1,
          "td_height_ratio": 0.9,
          "td_length_ratio": 0.4,
          "td_maxheight": 2.0,
          "td_maxlen": 1.0,
          "td_on_pad_in_zone": false,
          "td_target_name": "td_round_shape",
          "td_width_to_size_filter_ratio": 0.9
        },
        {
          "td_allow_use_two_tracks": true,
          "td_curve_segcount": 1,
          "td_height_ratio": 0.9,
          "td_length_ratio": 0.2,
          "td_maxheight": 2.0,
          "td_maxlen": 1.0,
          "td_on_pad_in_zone": false,
          "td_target_name": "td_rect_shape",
          "td_width_to_size_filter_ratio": 0.9
        },
        {
          "td_allow_use_two_tracks": true,
          "td_curve_segcount": 1,
          "td_height_ratio": 1.0,
          "td_length_ratio": 0.5,
          "td_maxheight": 2.0,
          "td_maxlen": 1.0,
          "td_on_pad_in_zone": false,
          "td_target_name": "td_track_end",
          "td_width_to_size_filter_ratio": 0.9
        }
      ],
      "track_widths": [
        0.0,
        0.125,
        0.13,
        0.15,
        0.155,
        0.16,
        0.2,
        0.3,
        0.5,
        0.55,
        1.4
      ],
      "tuning_pattern_settings": {
        "diff_pair_defaults": {
          "corner_radius_percentage": 80,
          "corner_style": 1,
          "max_amplitude": 1.0,
          "min_amplitude": 0.2,
          "single_sided": false,
          "spacing": 1.0
        },
        "diff_pair_skew_defaults": {
          "corner_radius_percentage": 80,
          "corner_style": 1,
          "max_amplitude": 1.0,
          "min_amplitude": 0.2,
          "single_sided": false,
          "spacing": 0.6
        },
        "single_track_defaults": {
          "corner_radius_percentage": 80,
          "corner_style": 1,
          "max_amplitude": 1.0,
          "min_amplitude": 0.2,
          "single_sided": false,
          "spacing": 0.6
        }
      },
      "via_dimensions": [
        {
          "diameter": 0.0,
          "drill": 0.0
        },
        {
          "diameter": 0.45,
          "drill": 0.1
        },
        {
          "diameter": 1.0,
          "drill": 0.5
        }
      ],
      "zones_allow_external_fillets": false
    },
    "ipc2581": {
      "dist": "",
      "distpn": "",
      "internal_id": "",
      "mfg": "",
      "mpn": ""
    },
    "layer_pairs": [],
    "layer_presets": [],
    "viewports": []
  },
  "boards": [],
  "cvpcb": {
    "equivalence_files": []
  },
  "erc": {
    "erc_exclusions": [],
    "meta": {
      "version": 0
    },
    "pin_map": [
      [
        0,
        0,
        0,
        0,
        0,
        0,
        1,
        0,
        0,
        0,
        0,
        2
      ],
      [
        0,
        2,
        0,
        1,
        0,
        0,
        1,
        0,
        2,
        2,
        2,
        2
      ],
      [
        0,
        0,
        0,
        0,
        0,
        0,
        1,
        0,
        1,
        0,
        1,
        2
      ],
      [
        0,
        1,
        0,
        0,
        0,
        0,
        1,
        1,
        2,
        1,
        1,
        2
      ],
      [
        0,
        0,
        0,
        0,
        0,
        0,
        1,
        0,
        0,
        0,
        0,
        2
      ],
      [
        0,
        0,
        0,
        0,
        0,
        0,
        0,
        0,
        0,
        0,
        0,
        2
      ],
      [
        1,
        1,
        1,
        1,
        1,
        0,
        1,
        1,
        1,
        1,
        1,
        2
      ],
      [
        0,
        0,
        0,
        1,
        0,
        0,
        1,
        0,
        0,
        0,
        0,
        2
      ],
      [
        0,
        2,
        1,
        2,
        0,
        0,
        1,
        0,
        2,
        2,
        2,
        2
      ],
      [
        0,
        2,
        0,
        1,
        0,
        0,
        1,
        0,
        2,
        0,
        0,
        2
      ],
      [
        0,
        2,
        1,
        1,
        0,
        0,
        1,
        0,
        2,
        0,
        0,
        2
      ],
      [
        2,
        2,
        2,
        2,
        2,
        2,
        2,
        2,
        2,
        2,
        2,
        2
      ]
    ],
    "rule_severities": {
      "bus_definition_conflict": "error",
      "bus_entry_needed": "error",
      "bus_to_bus_conflict": "error",
      "bus_to_net_conflict": "error",
      "conflicting_netclasses": "error",
      "different_unit_footprint": "error",
      "different_unit_net": "error",
      "duplicate_reference": "error",
      "duplicate_sheet_names": "error",
      "endpoint_off_grid": "warning",
      "extra_units": "error",
      "footprint_filter": "ignore",
      "footprint_link_issues": "warning",
      "four_way_junction": "ignore",
      "global_label_dangling": "warning",
      "hier_label_mismatch": "error",
      "label_dangling": "error",
      "label_multiple_wires": "warning",
      "lib_symbol_issues": "ignore",
      "lib_symbol_mismatch": "warning",
      "missing_bidi_pin": "warning",
      "missing_input_pin": "warning",
      "missing_power_pin": "error",
      "missing_unit": "warning",
      "multiple_net_names": "warning",
      "net_not_bus_member": "warning",
      "no_connect_connected": "warning",
      "no_connect_dangling": "warning",
      "pin_not_connected": "error",
      "pin_not_driven": "ignore",
      "pin_to_pin": "ignore",
      "power_pin_not_driven": "error",
      "same_local_global_label": "warning",
      "similar_label_and_power": "warning",
      "similar_labels": "ignore",
      "similar_power": "warning",
      "simulation_model_issue": "ignore",
      "single_global_label": "ignore",
      "unannotated": "error",
      "unconnected_wire_endpoint": "warning",
      "unit_value_mismatch": "error",
      "unresolved_variable": "error",
      "wire_dangling": "error"
    }
  },
  "libraries": {
    "pinned_footprint_libs": [],
    "pinned_symbol_libs": []
  },
  "meta": {
    "filename": "com-express-7-baseboard.kicad_pro",
    "version": 3
  },
  "net_settings": {
    "classes": [
      {
        "bus_width": 12,
        "clearance": 0.125,
        "diff_pair_gap": 0.25,
        "diff_pair_via_gap": 0.25,
        "diff_pair_width": 0.2,
        "line_style": 0,
        "microvia_diameter": 0.3,
        "microvia_drill": 0.1,
        "name": "Default",
        "pcb_color": "rgba(0, 0, 0, 0.000)",
        "priority": 2147483647,
        "schematic_color": "rgba(0, 0, 0, 0.000)",
        "track_width": 0.2,
        "via_diameter": 0.45,
        "via_drill": 0.1,
        "wire_width": 6
      },
      {
        "bus_width": 12,
        "clearance": 0.125,
        "diff_pair_gap": 0.22,
        "diff_pair_via_gap": 0.25,
        "diff_pair_width": 0.16,
        "line_style": 0,
        "microvia_diameter": 0.3,
        "microvia_drill": 0.1,
        "name": "100Ohm-diff_10GKR",
        "pcb_color": "rgb(255, 0, 40)",
        "priority": 0,
        "schematic_color": "rgba(0, 0, 0, 0.000)",
        "track_width": 0.25,
        "via_diameter": 0.45,
        "via_drill": 0.1,
        "wire_width": 6
      },
      {
        "bus_width": 12,
        "clearance": 0.125,
        "diff_pair_gap": 0.2,
        "diff_pair_via_gap": 0.25,
        "diff_pair_width": 0.15,
        "line_style": 0,
        "microvia_diameter": 0.3,
        "microvia_drill": 0.1,
        "name": "100Ohm-diff_GbE",
        "pcb_color": "rgb(38, 255, 27)",
        "priority": 1,
        "schematic_color": "rgba(0, 0, 0, 0.000)",
        "track_width": 0.25,
        "via_diameter": 0.45,
        "via_drill": 0.1,
        "wire_width": 6
      },
      {
        "bus_width": 12,
        "clearance": 0.125,
        "diff_pair_gap": 0.22,
        "diff_pair_via_gap": 0.25,
        "diff_pair_width": 0.16,
        "line_style": 0,
        "microvia_diameter": 0.3,
        "microvia_drill": 0.1,
        "name": "100Ohm-diff_SFI",
        "pcb_color": "rgb(255, 0, 19)",
        "priority": 2,
        "schematic_color": "rgba(0, 0, 0, 0.000)",
        "track_width": 0.25,
        "via_diameter": 0.45,
        "via_drill": 0.1,
        "wire_width": 6
      },
      {
        "bus_width": 12,
        "clearance": 0.125,
        "diff_pair_gap": 0.25,
        "diff_pair_via_gap": 0.25,
        "diff_pair_width": 0.2,
        "line_style": 0,
        "microvia_diameter": 0.3,
        "microvia_drill": 0.1,
        "name": "50Ohm-se",
        "pcb_color": "rgb(31, 242, 255)",
        "priority": 3,
        "schematic_color": "rgba(0, 0, 0, 0.000)",
        "track_width": 0.182,
        "via_diameter": 0.45,
        "via_drill": 0.1,
        "wire_width": 6
      },
      {
        "bus_width": 12,
        "clearance": 0.125,
        "diff_pair_gap": 0.187,
        "diff_pair_via_gap": 0.25,
        "diff_pair_width": 0.202,
        "line_style": 0,
        "microvia_diameter": 0.3,
        "microvia_drill": 0.1,
        "name": "85Ohm-diff_PCIe",
        "pcb_color": "rgb(255, 45, 181)",
        "priority": 4,
        "schematic_color": "rgba(0, 0, 0, 0.000)",
        "track_width": 0.2,
        "via_diameter": 0.45,
        "via_drill": 0.1,
        "wire_width": 6
      },
      {
        "bus_width": 12,
        "clearance": 0.125,
        "diff_pair_gap": 0.195,
        "diff_pair_via_gap": 0.25,
        "diff_pair_width": 0.185,
        "line_style": 0,
        "microvia_diameter": 0.3,
        "microvia_drill": 0.1,
        "name": "90Ohm-diff_USB",
        "pcb_color": "rgb(25, 22, 255)",
        "priority": 5,
        "schematic_color": "rgba(0, 0, 0, 0.000)",
        "track_width": 0.2,
        "via_diameter": 0.45,
        "via_drill": 0.1,
        "wire_width": 6
      }
    ],
    "meta": {
      "version": 4
    },
    "net_colors": null,
    "netclass_assignments": null,
    "netclass_patterns": [
      {
        "netclass": "85Ohm-diff_PCIe",
        "pattern": "*PCIe*+"
      },
      {
        "netclass": "85Ohm-diff_PCIe",
        "pattern": "*PCIe*-"
      },
      {
        "netclass": "100Ohm-diff_SFI",
        "pattern": "*SFI*+"
      },
      {
        "netclass": "100Ohm-diff_SFI",
        "pattern": "*SFI*-"
      },
      {
        "netclass": "100Ohm-diff_GbE",
        "pattern": "*GbE*+"
      },
      {
        "netclass": "100Ohm-diff_GbE",
        "pattern": "*GbE*-"
      },
      {
        "netclass": "100Ohm-diff_10GKR",
        "pattern": "*10GKR*"
      },
      {
        "netclass": "90Ohm-diff_USB",
        "pattern": "*Backplane/USB*"
      },
      {
        "netclass": "90Ohm-diff_USB",
        "pattern": "*2xUSB3.0*X*"
      },
      {
        "netclass": "100Ohm-diff_GbE",
        "pattern": "*RJ45/D*"
      },
      {
        "netclass": "90Ohm-diff_USB",
        "pattern": "*2xUSB3.0*P*D*"
      },
      {
        "netclass": "90Ohm-diff_USB",
        "pattern": "*2xUSB3.0*USB_*D*"
      },
      {
        "netclass": "85Ohm-diff_PCIe",
        "pattern": "*PCIE_{REF}.CK*"
      },
      {
        "netclass": "90Ohm-diff_USB",
        "pattern": "*USB_D*"
      },
      {
        "netclass": "50Ohm-se",
        "pattern": "*Com*SDIO*"
      },
      {
        "netclass": "90Ohm-diff_USB",
        "pattern": "*USB*FTDI_D*"
      },
      {
        "netclass": "90Ohm-diff_USB",
        "pattern": "*USB1.D*"
      }
    ]
  },
  "pcbnew": {
    "last_paths": {
      "gencad": "",
      "idf": "",
      "netlist": "",
      "plot": "",
      "pos_files": "",
      "specctra_dsn": "",
      "step": "",
      "svg": "",
      "vrml": ""
    },
    "page_layout_descr_file": ""
  },
  "schematic": {
    "annotate_start_num": 0,
    "bom_export_filename": "",
    "bom_fmt_presets": [],
    "bom_fmt_settings": {
      "field_delimiter": ",",
      "keep_line_breaks": false,
      "keep_tabs": false,
      "name": "CSV",
      "ref_delimiter": ",",
      "ref_range_delimiter": "",
      "string_delimiter": "\""
    },
    "bom_presets": [],
    "bom_settings": {
      "exclude_dnp": false,
      "fields_ordered": [
        {
          "group_by": false,
          "label": "Reference",
          "name": "Reference",
          "show": true
        },
        {
          "group_by": true,
          "label": "Value",
          "name": "Value",
          "show": true
        },
        {
          "group_by": false,
          "label": "Datasheet",
          "name": "Datasheet",
          "show": true
        },
        {
          "group_by": false,
          "label": "Footprint",
          "name": "Footprint",
          "show": true
        },
        {
          "group_by": false,
          "label": "Qty",
          "name": "${QUANTITY}",
          "show": true
        },
        {
          "group_by": true,
          "label": "DNP",
          "name": "${DNP}",
          "show": true
        }
      ],
      "filter_string": "",
      "group_symbols": true,
      "include_excluded_from_bom": false,
      "name": "Grouped By Value",
      "sort_asc": true,
      "sort_field": "Reference"
    },
    "connection_grid_size": 50.0,
    "drawing": {
      "dashed_lines_dash_length_ratio": 12.0,
      "dashed_lines_gap_length_ratio": 3.0,
      "default_line_thickness": 6.0,
      "default_text_size": 50.0,
      "field_names": [],
      "intersheets_ref_own_page": false,
      "intersheets_ref_prefix": "",
      "intersheets_ref_short": false,
      "intersheets_ref_show": false,
      "intersheets_ref_suffix": "",
      "junction_size_choice": 3,
      "label_size_ratio": 0.375,
      "operating_point_overlay_i_precision": 3,
      "operating_point_overlay_i_range": "~A",
      "operating_point_overlay_v_precision": 3,
      "operating_point_overlay_v_range": "~V",
      "overbar_offset_ratio": 1.23,
      "pin_symbol_size": 25.0,
      "text_offset_ratio": 0.15
    },
    "legacy_lib_dir": "",
    "legacy_lib_list": [],
    "meta": {
      "version": 1
    },
    "net_format_name": "",
    "page_layout_descr_file": "",
    "plot_directory": "",
    "space_save_all_events": true,
    "spice_current_sheet_as_root": false,
    "spice_external_command": "spice \"%I\"",
    "spice_model_current_sheet_as_root": true,
    "spice_save_all_currents": false,
    "spice_save_all_dissipations": false,
    "spice_save_all_voltages": false,
    "subpart_first_id": 65,
    "subpart_id_separator": 0
  },
  "sheets": [
    [
      "",
      "Root"
    ],
    [
      "",
      "2xUSB3.0+RJ45"
    ],
    [
      "",
      "2xSFP+"
    ],
    [
      "",
      "USB-C console"
    ],
    [
      "",
      "OCuLink"
    ],
    [
      "",
      "Backplane"
    ],
    [
      "",
      "Power"
    ],
    [
      "",
      "M.2 key M #1"
    ],
    [
      "",
      "M.2 key M #2"
    ],
    [
      "",
      "M.2 key E"
    ],
    [
      "",
      "Misc"
    ],
    [
      "",
      "Com Express 7 Interfaces"
    ],
    [
      "",
      "Com Express 7 MGMT"
    ],
    [
      "",
      "PCIe misc"
    ],
    [
      "",
      "PCIe redriver"
    ],
    [
      "",
      "GPIO expander"
    ],
    [
      "",
      "KR to SFI #1"
    ],
    [
      "",
      "KR to SFI #2"
    ],
    [
      "",
      "SD card"
    ]
  ],
  "text_variables": {}
}
